# BASEBOARD_FAB2 (Tioga Pass) — schematic netlist excerpt (pin names and nets, part order shuffled) for the footprints in the layout excerpt that follows; sources: Cadence DE-HDL packaged netlist, KiCad conversion of Wiwynn_Tioga_Pass_MB.brd

J4A1  SCONN288_H44441004  SCONN  pkg PIP  page 53
  \12v\(1)  = P12V_NVDIMM_DEF
  VSS(93)  = GND
  DQ(4)  = M_F_DQ<5>
  VSS(92)  = GND
  DQ(0)  = M_F_DQ<1>
  VSS(91)  = GND
  DQS9P  = M_F_DQS_DP<9>
  DQS9N  = M_F_DQS_DN<9>
  VSS(90)  = GND
  DQ(6)  = M_F_DQ<7>
  VSS(89)  = GND
  DQ(2)  = M_F_DQ<3>
  VSS(88)  = GND
  DQ(12)  = M_F_DQ<13>
  VSS(87)  = GND
  DQ(8)  = M_F_DQ<9>
  VSS(86)  = GND
  DQS10P  = M_F_DQS_DP<10>
  DQS10N  = M_F_DQS_DN<10>
  VSS(85)  = GND
  DQ(14)  = M_F_DQ<15>
  VSS(84)  = GND
  DQ(10)  = M_F_DQ<11>
  VSS(83)  = GND
  DQ(20)  = M_F_DQ<21>
  VSS(82)  = GND
  DQ(16)  = M_F_DQ<17>
  VSS(81)  = GND
  DQS11P  = M_F_DQS_DP<11>
  DQS11N  = M_F_DQS_DN<11>
  VSS(80)  = GND
  DQ(22)  = M_F_DQ<23>
  VSS(79)  = GND
  DQ(18)  = M_F_DQ<19>
  VSS(78)  = GND
  DQ(28)  = M_F_DQ<29>
  VSS(77)  = GND
  DQ(24)  = M_F_DQ<25>
  VSS(76)  = GND
  DQS12P  = M_F_DQS_DP<12>
  DQS12N  = M_F_DQS_DN<12>
  VSS(75)  = GND
  DQ(30)  = M_F_DQ<31>
  VSS(74)  = GND
  DQ(26)  = M_F_DQ<27>
  VSS(73)  = GND
  CB(4)  = M_F_ECC<5>
  VSS(72)  = GND
  CB(0)  = M_F_ECC<1>
  VSS(71)  = GND
  DQS17P  = M_F_DQS_DP<17>
  DQS17N  = M_F_DQS_DN<17>
  VSS(70)  = GND
  CB(6)  = M_F_ECC<7>
  VSS(69)  = GND
  CB(2)  = M_F_ECC<3>
  VSS(68)  = GND
  RESET_N  = M_DEF_RST_N
  VDD(25)  = PVDDQ_DEF
  CKE(0)  = M_F_CKE<0>
  VDD(24)  = PVDDQ_DEF
  ACT_N  = M_F_ACT_N
  BG(0)  = M_F_BG<0>
  VDD(23)  = PVDDQ_DEF
  A12  = M_F_MA<12>
  A9  = M_F_MA<9>
  VDD(22)  = PVDDQ_DEF
  A8  = M_F_MA<8>
  A6  = M_F_MA<6>
  VDD(21)  = PVDDQ_DEF
  A3  = M_F_MA<3>
  A1  = M_F_MA<1>
  VDD(20)  = PVDDQ_DEF
  CK0P  = M_F_CLK_DP<0>
  CK0N  = M_F_CLK_DN<0>
  VDD(19)  = PVDDQ_DEF
  VTT(1)  = PVTT_DEF
  EVENT_N  = FM_DIMM_EVENT_COD_N
  A0  = M_F_MA<0>
  VDD(18)  = PVDDQ_DEF
  BA(0)  = M_F_BA<0>
  A16_RAS_N  = M_F_MA<16>
  VDD(17)  = PVDDQ_DEF
  S0_N  = M_F_CS_N<0>
  VDD(16)  = PVDDQ_DEF
  A15_CAS_N  = M_F_MA<15>
  ODT(0)  = M_F_ODT<0>
  VDD(15)  = PVDDQ_DEF
  S1_N  = M_F_CS_N<1>
  VDD(14)  = PVDDQ_DEF
  ODT(1)  = M_F_ODT<1>
  VDD(13)  = PVDDQ_DEF
  S2_N_C(0)  = M_F_CS_N<2>
  VSS(67)  = GND
  DQ(36)  = M_F_DQ<37>
  VSS(66)  = GND
  DQ(32)  = M_F_DQ<33>
  VSS(65)  = GND
  DQS13P  = M_F_DQS_DP<13>
  DQS13N  = M_F_DQS_DN<13>
  VSS(64)  = GND
  DQ(38)  = M_F_DQ<39>
  VSS(63)  = GND
  DQ(34)  = M_F_DQ<35>
  VSS(62)  = GND
  DQ(44)  = M_F_DQ<45>
  VSS(61)  = GND
  DQ(40)  = M_F_DQ<41>
  VSS(60)  = GND
  DQS14P  = M_F_DQS_DP<14>
  DQS14N  = M_F_DQS_DN<14>
  VSS(59)  = GND
  DQ(46)  = M_F_DQ<47>
  VSS(58)  = GND
  DQ(42)  = M_F_DQ<43>
  VSS(57)  = GND
  DQ(52)  = M_F_DQ<53>
  VSS(56)  = GND
  DQ(48)  = M_F_DQ<49>
  VSS(55)  = GND
  DQS15P  = M_F_DQS_DP<15>
  DQS15N  = M_F_DQS_DN<15>
  VSS(54)  = GND
  DQ(54)  = M_F_DQ<55>
  VSS(53)  = GND
  DQ(50)  = M_F_DQ<51>
  VSS(52)  = GND
  DQ(60)  = M_F_DQ<61>
  VSS(51)  = GND
  DQ(56)  = M_F_DQ<57>
  VSS(50)  = GND
  DQS16P  = M_F_DQS_DP<16>
  DQS16N  = M_F_DQS_DN<16>
  VSS(49)  = GND
  DQ(62)  = M_F_DQ<63>
  VSS(48)  = GND
  DQ(58)  = M_F_DQ<59>
  VSS(47)  = GND
  SA(0)  = GND
  SA(1)  = GND
  SCL  = SMB_DDR_DEF_VPP_SCL
  VPP(4)  = PVPP_DEF
  VPP(3)  = PVPP_DEF
  RFU(2)  = TP_CH_F_DIMM_F0_RFU_2
  \12v\(0)  = P12V_NVDIMM_DEF
  VREFCA  = M_F_VREF
  VSS(46)  = GND
  DQ(5)  = M_F_DQ<4>
  VSS(45)  = GND
  DQ(1)  = M_F_DQ<0>
  VSS(44)  = GND
  DQS0N  = M_F_DQS_DN<0>
  DQS0P  = M_F_DQS_DP<0>
  VSS(43)  = GND
  DQ(7)  = M_F_DQ<6>
  VSS(42)  = GND
  DQ(3)  = M_F_DQ<2>
  VSS(41)  = GND
  DQ(13)  = M_F_DQ<12>
  VSS(40)  = GND
  DQ(9)  = M_F_DQ<8>
  VSS(39)  = GND
  DQS1N  = M_F_DQS_DN<1>
  DQS1P  = M_F_DQS_DP<1>
  VSS(38)  = GND
  DQ(15)  = M_F_DQ<14>
  VSS(37)  = GND
  DQ(11)  = M_F_DQ<10>
  VSS(36)  = GND
  DQ(21)  = M_F_DQ<20>
  VSS(35)  = GND
  DQ(17)  = M_F_DQ<16>
  VSS(34)  = GND
  DQS2N  = M_F_DQS_DN<2>
  DQS2P  = M_F_DQS_DP<2>
  VSS(33)  = GND
  DQ(23)  = M_F_DQ<22>
  VSS(32)  = GND
  DQ(19)  = M_F_DQ<18>
  VSS(31)  = GND
  DQ(29)  = M_F_DQ<28>
  VSS(30)  = GND
  DQ(25)  = M_F_DQ<24>
  VSS(29)  = GND
  DQS3N  = M_F_DQS_DN<3>
  DQS3P  = M_F_DQS_DP<3>
  VSS(28)  = GND
  DQ(31)  = M_F_DQ<30>
  VSS(27)  = GND
  DQ(27)  = M_F_DQ<26>
  VSS(26)  = GND
  CB(5)  = M_F_ECC<4>
  VSS(25)  = GND
  CB(1)  = M_F_ECC<0>
  VSS(24)  = GND
  DQS8N  = M_F_DQS_DN<8>
  DQS8P  = M_F_DQS_DP<8>
  VSS(23)  = GND
  CB(7)  = M_F_ECC<6>
  VSS(22)  = GND
  CB(3)  = M_F_ECC<2>
  VSS(21)  = GND
  CKE(1)  = M_F_CKE<1>
  VDD(12)  = PVDDQ_DEF
  RFU(0)  = TP_CH_F_DIMM_F0_RFU_0
  VDD(11)  = PVDDQ_DEF
  BG(1)  = M_F_BG<1>
  ALERT_N  = M_F_ALERT_N
  VDD(10)  = PVDDQ_DEF
  A11  = M_F_MA<11>
  A7  = M_F_MA<7>
  VDD(9)  = PVDDQ_DEF
  A5  = M_F_MA<5>
  A4  = M_F_MA<4>
  VDD(8)  = PVDDQ_DEF
  A2  = M_F_MA<2>
  VDD(7)  = PVDDQ_DEF
  CK1P  = M_F_CLK_DP<1>
  CK1N  = M_F_CLK_DN<1>
  VDD(6)  = PVDDQ_DEF
  VTT(0)  = PVTT_DEF
  PAR  = M_F_PAR
  VDD(5)  = PVDDQ_DEF
  BA(1)  = M_F_BA<1>
  A10  = M_F_MA<10>
  VDD(4)  = PVDDQ_DEF
  RFU(1)  = TP_CH_F_DIMM_F0_RFU_1
  A14_WE_N  = M_F_MA<14>
  VDD(3)  = PVDDQ_DEF
  SAVE_N_NC  = FM_ADR_COMPLETE_DEF_N
  VDD(2)  = PVDDQ_DEF
  A13  = M_F_MA<13>
  VDD(1)  = PVDDQ_DEF
  A17  = M_F_MA<17>
  C(2)  = M_F_C<2>
  VDD(0)  = PVDDQ_DEF
  S3_N_C(1)  = M_F_CS_N<3>
  SA(2)  = PVPP_DEF
  VSS(20)  = GND
  DQ(37)  = M_F_DQ<36>
  VSS(19)  = GND
  DQ(33)  = M_F_DQ<32>
  VSS(18)  = GND
  DQS4N  = M_F_DQS_DN<4>
  DQS4P  = M_F_DQS_DP<4>
  VSS(17)  = GND
  DQ(39)  = M_F_DQ<38>
  VSS(16)  = GND
  DQ(35)  = M_F_DQ<34>
  VSS(15)  = GND
  DQ(45)  = M_F_DQ<44>
  VSS(14)  = GND
  DQ(41)  = M_F_DQ<40>
  VSS(13)  = GND
  DQS5N  = M_F_DQS_DN<5>
  DQS5P  = M_F_DQS_DP<5>
  VSS(12)  = GND
  DQ(47)  = M_F_DQ<46>
  VSS(11)  = GND
  DQ(43)  = M_F_DQ<42>
  VSS(10)  = GND
  DQ(53)  = M_F_DQ<52>
  VSS(9)  = GND
  DQ(49)  = M_F_DQ<48>
  VSS(8)  = GND
  DQS6N  = M_F_DQS_DN<6>
  DQS6P  = M_F_DQS_DP<6>
  VSS(7)  = GND
  DQ(55)  = M_F_DQ<54>
  VSS(6)  = GND
  DQ(51)  = M_F_DQ<50>
  VSS(5)  = GND
  DQ(61)  = M_F_DQ<60>
  VSS(4)  = GND
  DQ(57)  = M_F_DQ<56>
  VSS(3)  = GND
  DQS7N  = M_F_DQS_DN<7>
  DQS7P  = M_F_DQS_DP<7>
  VSS(2)  = GND
  DQ(63)  = M_F_DQ<62>
  VSS(1)  = GND
  DQ(59)  = M_F_DQ<58>
  VSS(0)  = GND
  VDDSPD  = PVPP_DEF
  SDA  = SMB_DDR_DEF_VPP_SDA
  VPP(1)  = PVPP_DEF
  VPP(0)  = PVPP_DEF
  VPP(2)  = PVPP_DEF

(kicad_pcb
	(version 20260206)
	(generator "pcbnew")
	(generator_version "10.0")
	(general
		(thickness 1.6)
		(legacy_teardrops no)
	)
	(paper "A4")
	(title_block
		(title "Wiwynn_Tioga_Pass_MB.brd")
		(comment 1 "Tioga Pass / footprint 431 of 4770 (J4A1), pads 102-152 of 291")
	)
	(layers
		(0 "F.Cu" signal "TOP")
		(4 "In1.Cu" signal "L2GND")
		(6 "In2.Cu" signal "L3")
		(8 "In3.Cu" signal "L4GND")
		(10 "In4.Cu" signal "L5")
		(12 "In5.Cu" signal "L6GND")
		(14 "In6.Cu" signal "L7VCC")
		(16 "In7.Cu" signal "L8VCC")
		(18 "In8.Cu" signal "L9GND")
		(20 "In9.Cu" signal "L10")
		(22 "In10.Cu" signal "L11GND")
		(24 "In11.Cu" signal "L12")
		(26 "In12.Cu" signal "L13GND")
		(2 "B.Cu" signal "BOTTOM")
		(9 "F.Adhes" user "F.Adhesive")
		(11 "B.Adhes" user "B.Adhesive")
		(13 "F.Paste" user "Package Geometry/Pastemask Top")
		(15 "B.Paste" user "Package Geometry/Pastemask Bottom")
		(5 "F.SilkS" user "Ref Des/Silkscreen Top")
		(7 "B.SilkS" user "Ref Des/Silkscreen Bottom")
		(1 "F.Mask" user "Board Geometry/Soldermask Top")
		(3 "B.Mask" user "Board Geometry/Soldermask Bottom")
		(17 "Dwgs.User" user "User.Drawings")
		(19 "Cmts.User" user "User.Comments")
		(21 "Eco1.User" user "User.Eco1")
		(23 "Eco2.User" user "User.Eco2")
		(25 "Edge.Cuts" user "Board Geometry/Outline")
		(27 "Margin" user)
		(31 "F.CrtYd" user "Package Geometry/Place Bound Top")
		(29 "B.CrtYd" user "Package Geometry/Place Bound Bottom")
		(35 "F.Fab" user "Ref Des/Assembly Top")
		(33 "B.Fab" user "Ref Des/Assembly Bottom")
	)
	(footprint ""
		(layer "F.Cu")
		(at 194.700398 -152.273 90)
		(property "Reference" "J4A1"
			(at -2.699512 42.53611 0)
			(unlocked yes)
			(layer "F.SilkS")
			(effects
				(font
					(size 0.7874 0.5842)
					(thickness 0.1524)
				)
				(justify left)
			)
		)
		(property "Value" ""
			(at 0 0 90)
			(layer "F.Fab")
			(effects
				(font
					(size 1.27 1.27)
				)
			)
		)
		(duplicate_pad_numbers_are_jumpers no)
		(pad "99" smd rect
			(at 0 88.399874 90)
			(size 1.8034 0.508)
			(layers "F.Cu" "F.Mask" "F.Paste")
			(net "M_F_DQS_DP<13>")
		)
		(pad "100" smd rect
			(at 0 89.250012 90)
			(size 1.8034 0.508)
			(layers "F.Cu" "F.Mask" "F.Paste")
			(net "M_F_DQS_DN<13>")
		)
		(pad "101" smd rect
			(at 0 90.099896 90)
			(size 1.8034 0.508)
			(layers "F.Cu" "F.Mask" "F.Paste")
			(net "GND")
		)
		(pad "102" smd rect
			(at 0 90.950034 90)
			(size 1.8034 0.508)
			(layers "F.Cu" "F.Mask" "F.Paste")
			(net "M_F_DQ<39>")
		)
		(pad "103" smd rect
			(at 0 91.799918 90)
			(size 1.8034 0.508)
			(layers "F.Cu" "F.Mask" "F.Paste")
			(net "GND")
		)
		(pad "104" smd rect
			(at 0 92.650056 90)
			(size 1.8034 0.508)
			(layers "F.Cu" "F.Mask" "F.Paste")
			(net "M_F_DQ<35>")
		)
		(pad "105" smd rect
			(at 0 93.49994 90)
			(size 1.8034 0.508)
			(layers "F.Cu" "F.Mask" "F.Paste")
			(net "GND")
		)
		(pad "106" smd rect
			(at 0 94.350078 90)
			(size 1.8034 0.508)
			(layers "F.Cu" "F.Mask" "F.Paste")
			(net "M_F_DQ<45>")
		)
		(pad "107" smd rect
			(at 0 95.199962 90)
			(size 1.8034 0.508)
			(layers "F.Cu" "F.Mask" "F.Paste")
			(net "GND")
		)
		(pad "108" smd rect
			(at 0 96.0501 90)
			(size 1.8034 0.508)
			(layers "F.Cu" "F.Mask" "F.Paste")
			(net "M_F_DQ<41>")
		)
		(pad "109" smd rect
			(at 0 96.899984 90)
			(size 1.8034 0.508)
			(layers "F.Cu" "F.Mask" "F.Paste")
			(net "GND")
		)
		(pad "110" smd rect
			(at 0 97.750122 90)
			(size 1.8034 0.508)
			(layers "F.Cu" "F.Mask" "F.Paste")
			(net "M_F_DQS_DP<14>")
		)
		(pad "111" smd rect
			(at 0 98.600006 90)
			(size 1.8034 0.508)
			(layers "F.Cu" "F.Mask" "F.Paste")
			(net "M_F_DQS_DN<14>")
		)
		(pad "112" smd rect
			(at 0 99.44989 90)
			(size 1.8034 0.508)
			(layers "F.Cu" "F.Mask" "F.Paste")
			(net "GND")
		)
		(pad "113" smd rect
			(at 0 100.300028 90)
			(size 1.8034 0.508)
			(layers "F.Cu" "F.Mask" "F.Paste")
			(net "M_F_DQ<47>")
		)
		(pad "114" smd rect
			(at 0 101.149912 90)
			(size 1.8034 0.508)
			(layers "F.Cu" "F.Mask" "F.Paste")
			(net "GND")
		)
		(pad "115" smd rect
			(at 0 102.00005 90)
			(size 1.8034 0.508)
			(layers "F.Cu" "F.Mask" "F.Paste")
			(net "M_F_DQ<43>")
		)
		(pad "116" smd rect
			(at 0 102.849934 90)
			(size 1.8034 0.508)
			(layers "F.Cu" "F.Mask" "F.Paste")
			(net "GND")
		)
		(pad "117" smd rect
			(at 0 103.700072 90)
			(size 1.8034 0.508)
			(layers "F.Cu" "F.Mask" "F.Paste")
			(net "M_F_DQ<53>")
		)
		(pad "118" smd rect
			(at 0 104.549956 90)
			(size 1.8034 0.508)
			(layers "F.Cu" "F.Mask" "F.Paste")
			(net "GND")
		)
		(pad "119" smd rect
			(at 0 105.400094 90)
			(size 1.8034 0.508)
			(layers "F.Cu" "F.Mask" "F.Paste")
			(net "M_F_DQ<49>")
		)
		(pad "120" smd rect
			(at 0 106.249978 90)
			(size 1.8034 0.508)
			(layers "F.Cu" "F.Mask" "F.Paste")
			(net "GND")
		)
		(pad "121" smd rect
			(at 0 107.100116 90)
			(size 1.8034 0.508)
			(layers "F.Cu" "F.Mask" "F.Paste")
			(net "M_F_DQS_DP<15>")
		)
		(pad "122" smd rect
			(at 0 107.95 90)
			(size 1.8034 0.508)
			(layers "F.Cu" "F.Mask" "F.Paste")
			(net "M_F_DQS_DN<15>")
		)
		(pad "123" smd rect
			(at 0 108.799884 90)
			(size 1.8034 0.508)
			(layers "F.Cu" "F.Mask" "F.Paste")
			(net "GND")
		)
		(pad "124" smd rect
			(at 0 109.650022 90)
			(size 1.8034 0.508)
			(layers "F.Cu" "F.Mask" "F.Paste")
			(net "M_F_DQ<55>")
		)
		(pad "125" smd rect
			(at 0 110.499906 90)
			(size 1.8034 0.508)
			(layers "F.Cu" "F.Mask" "F.Paste")
			(net "GND")
		)
		(pad "126" smd rect
			(at 0 111.350044 90)
			(size 1.8034 0.508)
			(layers "F.Cu" "F.Mask" "F.Paste")
			(net "M_F_DQ<51>")
		)
		(pad "127" smd rect
			(at 0 112.199928 90)
			(size 1.8034 0.508)
			(layers "F.Cu" "F.Mask" "F.Paste")
			(net "GND")
		)
		(pad "128" smd rect
			(at 0 113.050066 90)
			(size 1.8034 0.508)
			(layers "F.Cu" "F.Mask" "F.Paste")
			(net "M_F_DQ<61>")
		)
		(pad "129" smd rect
			(at 0 113.89995 90)
			(size 1.8034 0.508)
			(layers "F.Cu" "F.Mask" "F.Paste")
			(net "GND")
		)
		(pad "130" smd rect
			(at 0 114.750088 90)
			(size 1.8034 0.508)
			(layers "F.Cu" "F.Mask" "F.Paste")
			(net "M_F_DQ<57>")
		)
		(pad "131" smd rect
			(at 0 115.599972 90)
			(size 1.8034 0.508)
			(layers "F.Cu" "F.Mask" "F.Paste")
			(net "GND")
		)
		(pad "132" smd rect
			(at 0 116.45011 90)
			(size 1.8034 0.508)
			(layers "F.Cu" "F.Mask" "F.Paste")
			(net "M_F_DQS_DP<16>")
		)
		(pad "133" smd rect
			(at 0 117.299994 90)
			(size 1.8034 0.508)
			(layers "F.Cu" "F.Mask" "F.Paste")
			(net "M_F_DQS_DN<16>")
		)
		(pad "134" smd rect
			(at 0 118.149878 90)
			(size 1.8034 0.508)
			(layers "F.Cu" "F.Mask" "F.Paste")
			(net "GND")
		)
		(pad "135" smd rect
			(at 0 119.000016 90)
			(size 1.8034 0.508)
			(layers "F.Cu" "F.Mask" "F.Paste")
			(net "M_F_DQ<63>")
		)
		(pad "136" smd rect
			(at 0 119.8499 90)
			(size 1.8034 0.508)
			(layers "F.Cu" "F.Mask" "F.Paste")
			(net "GND")
		)
		(pad "137" smd rect
			(at 0 120.700038 90)
			(size 1.8034 0.508)
			(layers "F.Cu" "F.Mask" "F.Paste")
			(net "M_F_DQ<59>")
		)
		(pad "138" smd rect
			(at 0 121.549922 90)
			(size 1.8034 0.508)
			(layers "F.Cu" "F.Mask" "F.Paste")
			(net "GND")
		)
		(pad "139" smd rect
			(at 0 122.40006 90)
			(size 1.8034 0.508)
			(layers "F.Cu" "F.Mask" "F.Paste")
			(net "GND")
		)
		(pad "140" smd rect
			(at 0 123.249944 90)
			(size 1.8034 0.508)
			(layers "F.Cu" "F.Mask" "F.Paste")
			(net "GND")
		)
		(pad "141" smd rect
			(at 0 124.100082 90)
			(size 1.8034 0.508)
			(layers "F.Cu" "F.Mask" "F.Paste")
			(net "SMB_DDR_DEF_VPP_SCL")
		)
		(pad "142" smd rect
			(at 0 124.949966 90)
			(size 1.8034 0.508)
			(layers "F.Cu" "F.Mask" "F.Paste")
			(net "PVPP_DEF")
		)
		(pad "143" smd rect
			(at 0 125.800104 90)
			(size 1.8034 0.508)
			(layers "F.Cu" "F.Mask" "F.Paste")
			(net "PVPP_DEF")
		)
		(pad "144" smd rect
			(at 0 126.649988 90)
			(size 1.8034 0.508)
			(layers "F.Cu" "F.Mask" "F.Paste")
			(net "TP_CH_F_DIMM_F0_RFU_2")
		)
		(pad "145" smd rect
			(at 4.59994 0 90)
			(size 1.8034 0.508)
			(layers "F.Cu" "F.Mask" "F.Paste")
			(net "P12V_NVDIMM_DEF")
		)
		(pad "146" smd rect
			(at 4.59994 0.849884 90)
			(size 1.8034 0.508)
			(layers "F.Cu" "F.Mask" "F.Paste")
			(net "M_F_VREF")
		)
		(pad "147" smd rect
			(at 4.59994 1.700022 90)
			(size 1.8034 0.508)
			(layers "F.Cu" "F.Mask" "F.Paste")
			(net "GND")
		)
		(pad "148" smd rect
			(at 4.59994 2.549906 90)
			(size 1.8034 0.508)
			(layers "F.Cu" "F.Mask" "F.Paste")
			(net "M_F_DQ<4>")
		)
		(pad "149" smd rect
			(at 4.59994 3.400044 90)
			(size 1.8034 0.508)
			(layers "F.Cu" "F.Mask" "F.Paste")
			(net "GND")
		)
	)
)
